# T6G (Grand Teton) — schematic netlist excerpt (pin names and nets, part order shuffled) for the footprints in the layout excerpt that follows; sources: Cadence DE-HDL packaged netlist, KiCad conversion of 04192023_DAF0TMB3IC0_F0TG_MB_C_brd_V02_OCP.brd

C2647  Q_CAP  22UF 4V 20% X6S  pkg C0402  page 70 : A = PVDD11_S3_P0 ; B = GND
R409  Q_RES  2.2K 5% CHIP  pkg 0402LF  page 27 : A = CPU0_BP1 ; B = PVDD18_S5_P0

(kicad_pcb
	(version 20260206)
	(generator "pcbnew")
	(generator_version "10.0")
	(general
		(thickness 1.6)
		(legacy_teardrops no)
	)
	(paper "A4")
	(title_block
		(title "04192023_DAF0TMB3IC0_F0TG_MB_C_brd_V02_OCP.brd")
		(comment 1 "Grand Teton / footprints 7251-7252 of 8354")
	)
	(layers
		(0 "F.Cu" signal "TOP")
		(4 "In1.Cu" signal "GND")
		(6 "In2.Cu" signal "IN1")
		(8 "In3.Cu" signal "GND1")
		(10 "In4.Cu" signal "IN2")
		(12 "In5.Cu" signal "GND2")
		(14 "In6.Cu" signal "IN3")
		(16 "In7.Cu" signal "GND3")
		(18 "In8.Cu" signal "VCC")
		(20 "In9.Cu" signal "VCC1")
		(22 "In10.Cu" signal "GND4")
		(24 "In11.Cu" signal "IN4")
		(26 "In12.Cu" signal "GND5")
		(28 "In13.Cu" signal "IN5")
		(30 "In14.Cu" signal "GND6")
		(32 "In15.Cu" signal "IN6")
		(34 "In16.Cu" signal "GND7")
		(2 "B.Cu" signal "BOTTOM")
		(9 "F.Adhes" user "F.Adhesive")
		(11 "B.Adhes" user "B.Adhesive")
		(13 "F.Paste" user "Package Geometry/Pastemask Top")
		(15 "B.Paste" user "Package Geometry/Pastemask Bottom")
		(5 "F.SilkS" user "Ref Des/Silkscreen Top")
		(7 "B.SilkS" user "Ref Des/Silkscreen Bottom")
		(1 "F.Mask" user "Board Geometry/Soldermask Top")
		(3 "B.Mask" user "Board Geometry/Soldermask Bottom")
		(17 "Dwgs.User" user "User.Drawings")
		(19 "Cmts.User" user "User.Comments")
		(21 "Eco1.User" user "User.Eco1")
		(23 "Eco2.User" user "User.Eco2")
		(25 "Edge.Cuts" user "Board Geometry/Outline")
		(27 "Margin" user)
		(31 "F.CrtYd" user "Package Geometry/Place Bound Top")
		(29 "B.CrtYd" user "Package Geometry/Place Bound Bottom")
		(35 "F.Fab" user "Ref Des/Assembly Top")
		(33 "B.Fab" user "Ref Des/Assembly Bottom")
	)
	(footprint ""
		(layer "B.Cu")
		(at 369.884706 -263.46531)
		(property "Reference" "C2647"
			(at 0 0 0)
			(layer "B.SilkS")
			(hide yes)
			(effects
				(font
					(size 1.27 1.27)
				)
				(justify mirror)
			)
		)
		(property "Value" ""
			(at 0 0 0)
			(layer "B.Fab")
			(effects
				(font
					(size 1.27 1.27)
				)
				(justify mirror)
			)
		)
		(duplicate_pad_numbers_are_jumpers no)
		(fp_line
			(start -0.7874 -0.4064)
			(end -0.7874 0.4064)
			(stroke
				(width 0.1524)
				(type default)
			)
			(layer "B.SilkS")
		)
		(fp_line
			(start -0.7874 0.4064)
			(end 0.7874 0.4064)
			(stroke
				(width 0.1524)
				(type default)
			)
			(layer "B.SilkS")
		)
		(fp_line
			(start 0.7874 -0.4064)
			(end -0.7874 -0.4064)
			(stroke
				(width 0.1524)
				(type default)
			)
			(layer "B.SilkS")
		)
		(fp_line
			(start 0.7874 0.4064)
			(end 0.7874 -0.4064)
			(stroke
				(width 0.1524)
				(type default)
			)
			(layer "B.SilkS")
		)
		(fp_line
			(start -0.67945 -0.3048)
			(end -0.67945 0.3048)
			(stroke
				(width 0.1)
				(type default)
			)
			(layer "B.Fab")
		)
		(fp_line
			(start -0.67945 0.3048)
			(end -0.120396 0.3048)
			(stroke
				(width 0.1)
				(type default)
			)
			(layer "B.Fab")
		)
		(fp_line
			(start -0.12065 -0.3048)
			(end -0.67945 -0.3048)
			(stroke
				(width 0.1)
				(type default)
			)
			(layer "B.Fab")
		)
		(fp_line
			(start -0.12065 -0.2794)
			(end -0.12065 -0.3048)
			(stroke
				(width 0.1)
				(type default)
			)
			(layer "B.Fab")
		)
		(fp_line
			(start -0.120396 0.2794)
			(end 0.12065 0.2794)
			(stroke
				(width 0.1)
				(type default)
			)
			(layer "B.Fab")
		)
		(fp_line
			(start -0.120396 0.3048)
			(end -0.120396 0.2794)
			(stroke
				(width 0.1)
				(type default)
			)
			(layer "B.Fab")
		)
		(fp_line
			(start 0.12065 -0.305054)
			(end 0.12065 -0.2794)
			(stroke
				(width 0.1)
				(type default)
			)
			(layer "B.Fab")
		)
		(fp_line
			(start 0.12065 -0.2794)
			(end -0.12065 -0.2794)
			(stroke
				(width 0.1)
				(type default)
			)
			(layer "B.Fab")
		)
		(fp_line
			(start 0.12065 0.2794)
			(end 0.12065 0.3048)
			(stroke
				(width 0.1)
				(type default)
			)
			(layer "B.Fab")
		)
		(fp_line
			(start 0.12065 0.3048)
			(end 0.67945 0.3048)
			(stroke
				(width 0.1)
				(type default)
			)
			(layer "B.Fab")
		)
		(fp_line
			(start 0.67945 -0.305054)
			(end 0.12065 -0.305054)
			(stroke
				(width 0.1)
				(type default)
			)
			(layer "B.Fab")
		)
		(fp_line
			(start 0.67945 0.3048)
			(end 0.67945 -0.305054)
			(stroke
				(width 0.1)
				(type default)
			)
			(layer "B.Fab")
		)
		(pad "1" smd circle
			(at 0.40005 0 180)
			(size 0 0)
			(layers "B.Cu" "B.Mask" "B.Paste")
			(net "PVDD11_S3_P0")
		)
		(pad "2" smd circle
			(at -0.40005 0 180)
			(size 0 0)
			(layers "B.Cu" "B.Mask" "B.Paste")
			(net "GND")
		)
	)
	(footprint ""
		(layer "B.Cu")
		(at 320.846958 -197.567296)
		(property "Reference" "R409"
			(at 0 0 0)
			(layer "B.SilkS")
			(hide yes)
			(effects
				(font
					(size 1.27 1.27)
				)
				(justify mirror)
			)
		)
		(property "Value" ""
			(at 0 0 0)
			(layer "B.Fab")
			(effects
				(font
					(size 1.27 1.27)
				)
				(justify mirror)
			)
		)
		(duplicate_pad_numbers_are_jumpers no)
		(fp_line
			(start -0.7874 -0.4064)
			(end -0.7874 0.4064)
			(stroke
				(width 0.1524)
				(type default)
			)
			(layer "B.SilkS")
		)
		(fp_line
			(start -0.7874 0.4064)
			(end 0.7874 0.4064)
			(stroke
				(width 0.1524)
				(type default)
			)
			(layer "B.SilkS")
		)
		(fp_line
			(start 0.7874 -0.4064)
			(end -0.7874 -0.4064)
			(stroke
				(width 0.1524)
				(type default)
			)
			(layer "B.SilkS")
		)
		(fp_line
			(start 0.7874 0.4064)
			(end 0.7874 -0.4064)
			(stroke
				(width 0.1524)
				(type default)
			)
			(layer "B.SilkS")
		)
		(fp_line
			(start -0.67945 -0.3048)
			(end -0.67945 0.3048)
			(stroke
				(width 0.1)
				(type default)
			)
			(layer "B.Fab")
		)
		(fp_line
			(start -0.67945 0.3048)
			(end -0.120396 0.3048)
			(stroke
				(width 0.1)
				(type default)
			)
			(layer "B.Fab")
		)
		(fp_line
			(start -0.12065 -0.3048)
			(end -0.67945 -0.3048)
			(stroke
				(width 0.1)
				(type default)
			)
			(layer "B.Fab")
		)
		(fp_line
			(start -0.12065 -0.2794)
			(end -0.12065 -0.3048)
			(stroke
				(width 0.1)
				(type default)
			)
			(layer "B.Fab")
		)
		(fp_line
			(start -0.120396 0.2794)
			(end 0.12065 0.2794)
			(stroke
				(width 0.1)
				(type default)
			)
			(layer "B.Fab")
		)
		(fp_line
			(start -0.120396 0.3048)
			(end -0.120396 0.2794)
			(stroke
				(width 0.1)
				(type default)
			)
			(layer "B.Fab")
		)
		(fp_line
			(start 0.12065 -0.305054)
			(end 0.12065 -0.2794)
			(stroke
				(width 0.1)
				(type default)
			)
			(layer "B.Fab")
		)
		(fp_line
			(start 0.12065 -0.2794)
			(end -0.12065 -0.2794)
			(stroke
				(width 0.1)
				(type default)
			)
			(layer "B.Fab")
		)
		(fp_line
			(start 0.12065 0.2794)
			(end 0.12065 0.3048)
			(stroke
				(width 0.1)
				(type default)
			)
			(layer "B.Fab")
		)
		(fp_line
			(start 0.12065 0.3048)
			(end 0.67945 0.3048)
			(stroke
				(width 0.1)
				(type default)
			)
			(layer "B.Fab")
		)
		(fp_line
			(start 0.67945 -0.305054)
			(end 0.12065 -0.305054)
			(stroke
				(width 0.1)
				(type default)
			)
			(layer "B.Fab")
		)
		(fp_line
			(start 0.67945 0.3048)
			(end 0.67945 -0.305054)
			(stroke
				(width 0.1)
				(type default)
			)
			(layer "B.Fab")
		)
		(pad "1" smd circle
			(at 0.40005 0 180)
			(size 0 0)
			(layers "B.Cu" "B.Mask" "B.Paste")
			(net "CPU0_BP1")
		)
		(pad "2" smd circle
			(at -0.40005 0 180)
			(size 0 0)
			(layers "B.Cu" "B.Mask" "B.Paste")
			(net "PVDD18_S5_P0")
		)
	)
)
